FILE_TYPE = MULTI_PHYS_TABLE;

PART 'CYUSB330468LTXI'

{========================================================================================}
:VALUE              | PART_TYPE | MATERIAL | PART_NUMBER    = STANDARD        | LIFECYCLE      | PART_NUMBER   | JEDEC_TYPE         | DESCRIPTION                         | MANUFTR | MANUF_PN           | RD_CMPLS_LVL | CMPLS_LVL | FROM_PJ     | CLASS | DIP_SMD | DATA                   | EE_CHECK_LIST | FP_ECN | PSL | CREATOR | STATUS | MSD  | ESD_CDM | ESD_HBM     | ESD_MM | PIN_LENGTH_SHORT_PIN | PIN_LENGTH_LONG_PIN | CREATEDAY  ;
{========================================================================================}
 'CYUSB3304-68LTXI' | 'SMLF'    | 'IC'     | 'AJ033040001'(!) = ''               | ''               | 'AJ033040001' |'QFN68_TH_0-4_8X8'| 'IC CTRL(68P)CYUSB3304-68LTXI(QFN)' | 'CYP'   | 'CYUSB3304-68LTXI' | 'EU(V1)'     | 'EP(V1)'  | 'S5M-ROGER' | 'IC'  | ''      | 'CYP_CYUSB3304-68LTXI' | ''            | ''     | ''  | ''      | ''     | 'NA' | 'NA'    | '+/- 2200V' | 'NA'   | '0 MILS'             | '0 MILS'            | '20170901'
 'CYUSB3304-68LTXI' | 'SMLF'    | 'EMPTY'  | 'AJ033040001'(!) = ''               | ''               | 'AJ033040001' |'QFN68_TH_0-4_8X8'| 'IC CTRL(68P)CYUSB3304-68LTXI(QFN)' | 'CYP'   | 'CYUSB3304-68LTXI' | 'EU(V1)'     | 'EP(V1)'  | 'S5M-ROGER' | 'IC'  | ''      | 'CYP_CYUSB3304-68LTXI' | ''            | ''     | ''  | ''      | ''     | 'NA' | 'NA'    | '+/- 2200V' | 'NA'   | '0 MILS'             | '0 MILS'            | '20170901'

END_PART

END.

